# T6G (Grand Teton) — schematic netlist excerpt (pin names and nets, part order shuffled) for the footprints in the layout excerpt that follows; sources: Cadence DE-HDL packaged netlist, KiCad conversion of 04192023_DAF0TMB3IC0_F0TG_MB_C_brd_V02_OCP.brd

J30  SCONN288_DDR506112002KQ  IO  pkg DDR288S_1-1VXC  page 101
  VIN_BULK0  = P12V_MEM_CPU1
  RFU0  = NC
  VIN_MGMT  = P3V3_AUX
  HSCL  = I3C_SPD_DDRD_CPU1_SCL
  HSDA  = I3C_SPD_DDRD_CPU1_SDA
  VSS0  = GND
  DQ0_A  = M_D_CPU1_SA_DQ<0>
  VSS1  = GND
  DQ1_A  = M_D_CPU1_SA_DQ<1>
  VSS2  = GND
  DQS0_A_T  = M_D_CPU1_SA_DQS_DP<0>
  DQS0_A_C  = M_D_CPU1_SA_DQS_DN<0>
  VSS3  = GND
  DQ4_A  = M_D_CPU1_SA_DQ<4>
  VSS4  = GND
  DQ5_A  = M_D_CPU1_SA_DQ<5>
  VSS5  = GND
  DQ8_A  = M_D_CPU1_SA_DQ<8>
  VSS6  = GND
  DQ9_A  = M_D_CPU1_SA_DQ<9>
  VSS7  = GND
  DQS1_A_T  = M_D_CPU1_SA_DQS_DP<1>
  DQS1_A_C  = M_D_CPU1_SA_DQS_DN<1>
  VSS8  = GND
  DQ12_A  = M_D_CPU1_SA_DQ<12>
  VSS9  = GND
  DQ13_A  = M_D_CPU1_SA_DQ<13>
  VSS10  = GND
  DQ16_A  = M_D_CPU1_SA_DQ<16>
  VSS11  = GND
  DQ17_A  = M_D_CPU1_SA_DQ<17>
  VSS12  = GND
  DQS2_A_T  = M_D_CPU1_SA_DQS_DP<2>
  DQS2_A_C  = M_D_CPU1_SA_DQS_DN<2>
  VSS13  = GND
  DQ20_A  = M_D_CPU1_SA_DQ<20>
  VSS14  = GND
  DQ21_A  = M_D_CPU1_SA_DQ<21>
  VSS15  = GND
  DQ24_A  = M_D_CPU1_SA_DQ<24>
  VSS16  = GND
  DQ25_A  = M_D_CPU1_SA_DQ<25>
  VSS17  = GND
  DQS3_A_T  = M_D_CPU1_SA_DQS_DP<3>
  DQS3_A_C  = M_D_CPU1_SA_DQS_DN<3>
  VSS18  = GND
  DQ28_A  = M_D_CPU1_SA_DQ<28>
  VSS19  = GND
  DQ29_A  = M_D_CPU1_SA_DQ<29>
  VSS20  = GND
  CB0_A  = M_D_CPU1_SA_CB<0>
  VSS21  = GND
  CB1_A  = M_D_CPU1_SA_CB<1>
  VSS22  = GND
  DQS4_A_T  = M_D_CPU1_SA_DQS_DP<4>
  DQS4_A_C  = M_D_CPU1_SA_DQS_DN<4>
  VSS23  = GND
  CB4_A  = M_D_CPU1_SA_CB<4>
  VSS24  = GND
  CB5_A  = M_D_CPU1_SA_CB<5>
  VSS25  = GND
  ALERT_N  = M_D_CPU1_ALERT_N
  VSS26  = GND
  CS0_A_N  = M_D_CPU1_SA_CS_N<0>
  VSS27  = GND
  CA0_A  = M_D_CPU1_SA_CA<0>
  VSS28  = GND
  CA2_A  = M_D_CPU1_SA_CA<2>
  VSS29  = GND
  CA4_A  = M_D_CPU1_SA_CA<4>
  VSS30  = GND
  CA6_A  = M_D_CPU1_SA_CA<6>
  VSS31  = GND
  PAR_A  = M_D_CPU1_SA_PAR
  VSS32  = GND
  CA0_B  = M_D_CPU1_SB_CA<0>
  VSS33  = GND
  CA2_B  = M_D_CPU1_SB_CA<2>
  VSS34  = GND
  CA4_B  = M_D_CPU1_SB_CA<4>
  VSS35  = GND
  CA6_B  = M_D_CPU1_SB_CA<6>
  VSS36  = GND
  CS0_B_N  = M_D_CPU1_SB_CS_N<0>
  VSS37  = GND
  \lbd||rsp_a_n\  = M_D_CPU1_SA_RSP<0>
  \lbs||rsp_b_n\  = M_D_CPU1_SB_RSP<0>
  VSS38  = GND
  CB4_B  = M_D_CPU1_SB_CB<4>
  VSS39  = GND
  CB5_B  = M_D_CPU1_SB_CB<5>
  VSS40  = GND
  \dqs9_b_t||tdqs9_b_t||dbi4_b_n\  = M_D_CPU1_SB_DQS_DP<9>
  \dqs9_b_c||tdqs9_b_c\  = M_D_CPU1_SB_DQS_DN<9>
  VSS41  = GND
  CB0_B  = M_D_CPU1_SB_CB<0>
  VSS42  = GND
  CB1_B  = M_D_CPU1_SB_CB<1>
  VSS43  = GND
  DQ0_B  = M_D_CPU1_SB_DQ<0>
  VSS44  = GND
  DQ1_B  = M_D_CPU1_SB_DQ<1>
  VSS45  = GND
  DQS0_B_T  = M_D_CPU1_SB_DQS_DP<0>
  DQS0_B_C  = M_D_CPU1_SB_DQS_DN<0>
  VSS46  = GND
  DQ4_B  = M_D_CPU1_SB_DQ<4>
  VSS47  = GND
  DQ5_B  = M_D_CPU1_SB_DQ<5>
  VSS48  = GND
  DQ8_B  = M_D_CPU1_SB_DQ<8>
  VSS49  = GND
  DQ9_B  = M_D_CPU1_SB_DQ<9>
  VSS50  = GND
  DQS1_B_T  = M_D_CPU1_SB_DQS_DP<1>
  DQS1_B_C  = M_D_CPU1_SB_DQS_DN<1>
  VSS51  = GND
  DQ12_B  = M_D_CPU1_SB_DQ<12>
  VSS52  = GND
  DQ13_B  = M_D_CPU1_SB_DQ<13>
  VSS53  = GND
  DQ16_B  = M_D_CPU1_SB_DQ<16>
  VSS54  = GND
  DQ17_B  = M_D_CPU1_SB_DQ<17>
  VSS55  = GND
  DQS2_B_T  = M_D_CPU1_SB_DQS_DP<2>
  DQS2_B_C  = M_D_CPU1_SB_DQS_DN<2>
  VSS56  = GND
  DQ20_B  = M_D_CPU1_SB_DQ<20>
  VSS57  = GND
  DQ21_B  = M_D_CPU1_SB_DQ<21>
  VSS58  = GND
  DQ24_B  = M_D_CPU1_SB_DQ<24>
  VSS59  = GND
  DQ25_B  = M_D_CPU1_SB_DQ<25>
  VSS60  = GND
  DQS3_B_T  = M_D_CPU1_SB_DQS_DP<3>
  DQS3_B_C  = M_D_CPU1_SB_DQS_DN<3>
  VSS61  = GND
  DQ28_B  = M_D_CPU1_SB_DQ<28>
  VSS62  = GND
  DQ29_B  = M_D_CPU1_SB_DQ<29>
  VSS63  = GND
  RFU1  = NC
  VIN_BULK1  = P12V_MEM_CPU1
  VIN_BULK2  = P12V_MEM_CPU1
  \pwr_good||fail_n\  = PWRGD_CHD_CPU1_DIMM
  HAS  = PD_CHD_CPU1_DIMM_SAA
  RFU2  = NC
  RFU3  = NC
  VSS64  = GND
  DQ2_A  = M_D_CPU1_SA_DQ<2>
  VSS65  = GND
  DQ3_A  = M_D_CPU1_SA_DQ<3>
  VSS66  = GND
  \dqs5_a_c||tdqs5_a_c||dqs5_a_t||tdqs5_a_t\  = M_D_CPU1_SA_DQS_DN<5>
  \dqs5_a_t||tdqs5_a_t\  = M_D_CPU1_SA_DQS_DP<5>
  VSS67  = GND
  DQ6_A  = M_D_CPU1_SA_DQ<6>
  VSS68  = GND
  DQ7_A  = M_D_CPU1_SA_DQ<7>
  VSS69  = GND
  DQ10_A  = M_D_CPU1_SA_DQ<10>
  VSS70  = GND
  DQ11_A  = M_D_CPU1_SA_DQ<11>
  VSS71  = GND
  \dqs6_a_c||tdqs6_a_c||dqs6_a_t||tdqs6_a_t\  = M_D_CPU1_SA_DQS_DN<6>
  \dqs6_a_t||tdqs6_a_t\  = M_D_CPU1_SA_DQS_DP<6>
  VSS72  = GND
  DQ14_A  = M_D_CPU1_SA_DQ<14>
  VSS73  = GND
  DQ15_A  = M_D_CPU1_SA_DQ<15>
  VSS74  = GND
  DQ18_A  = M_D_CPU1_SA_DQ<18>
  VSS75  = GND
  DQ19_A  = M_D_CPU1_SA_DQ<19>
  VSS76  = GND
  \dqs7_a_c||tdqs7_a_c\  = M_D_CPU1_SA_DQS_DN<7>
  \dqs7_a_t||tdqs7_a_t\  = M_D_CPU1_SA_DQS_DP<7>
  VSS77  = GND
  DQ22_A  = M_D_CPU1_SA_DQ<22>
  VSS78  = GND
  DQ23_A  = M_D_CPU1_SA_DQ<23>
  VSS79  = GND
  DQ26_A  = M_D_CPU1_SA_DQ<26>
  VSS80  = GND
  DQ27_A  = M_D_CPU1_SA_DQ<27>
  VSS81  = GND
  \dqs8_a_c||tdqs8_a_c\  = M_D_CPU1_SA_DQS_DN<8>
  \dqs8_a_t||tdqs8_a_t\  = M_D_CPU1_SA_DQS_DP<8>
  VSS82  = GND
  DQ30_A  = M_D_CPU1_SA_DQ<30>
  VSS83  = GND
  DQ31_A  = M_D_CPU1_SA_DQ<31>
  VSS84  = GND
  CB2_A  = M_D_CPU1_SA_CB<2>
  VSS85  = GND
  CB3_A  = M_D_CPU1_SA_CB<3>
  VSS86  = GND
  \dqs9_a_c||tdqs9_a_c\  = M_D_CPU1_SA_DQS_DN<9>
  \dqs9_a_t||tdqs9_a_t\  = M_D_CPU1_SA_DQS_DP<9>
  VSS87  = GND
  CB6_A  = M_D_CPU1_SA_CB<6>
  VSS88  = GND
  CB7_A  = M_D_CPU1_SA_CB<7>
  VSS89  = GND
  RESET_N  = M_D_CPU1_RESET_N
  VSS90  = GND
  CS1_A_N  = M_D_CPU1_SA_CS_N<1>
  VSS91  = GND
  CA1_A  = M_D_CPU1_SA_CA<1>
  VSS92  = GND
  CA3_A  = M_D_CPU1_SA_CA<3>
  VSS93  = GND
  CA5_A  = M_D_CPU1_SA_CA<5>
  VSS94  = GND
  CK_T  = M_D_CPU1_CLK_DP<0>
  CK_C  = M_D_CPU1_CLK_DN<0>
  VSS95  = GND
  RFU4  = NC
  CA1_B  = M_D_CPU1_SB_CA<1>
  VSS96  = GND
  CA3_B  = M_D_CPU1_SB_CA<3>
  VSS97  = GND
  CA5_B  = M_D_CPU1_SB_CA<5>
  VSS98  = GND
  PAR_B  = M_D_CPU1_SB_PAR
  VSS99  = GND
  CS1_B_N  = M_D_CPU1_SB_CS_N<1>
  VSS100  = GND
  RFU5  = NC
  RFU6  = NC
  VSS101  = GND
  CB6_B  = M_D_CPU1_SB_CB<6>
  VSS102  = GND
  CB7_B  = M_D_CPU1_SB_CB<7>
  VSS103  = GND
  DQS4_B_C  = M_D_CPU1_SB_DQS_DN<4>
  DQS4_B_T  = M_D_CPU1_SB_DQS_DP<4>
  VSS104  = GND
  CB2_B  = M_D_CPU1_SB_CB<2>
  VSS105  = GND
  CB3_B  = M_D_CPU1_SB_CB<3>
  VSS106  = GND
  DQ2_B  = M_D_CPU1_SB_DQ<2>
  VSS107  = GND
  DQ3_B  = M_D_CPU1_SB_DQ<3>
  VSS108  = GND
  \dqs5_b_c||tdqs5_b_c\  = M_D_CPU1_SB_DQS_DN<5>
  \dqs5_b_t||tdqs5_b_t\  = M_D_CPU1_SB_DQS_DP<5>
  VSS109  = GND
  DQ6_B  = M_D_CPU1_SB_DQ<6>
  VSS110  = GND
  DQ7_B  = M_D_CPU1_SB_DQ<7>
  VSS111  = GND
  DQ10_B  = M_D_CPU1_SB_DQ<10>
  VSS112  = GND
  DQ11_B  = M_D_CPU1_SB_DQ<11>
  VSS113  = GND
  \dqs6_b_c||tdqs6_b_c\  = M_D_CPU1_SB_DQS_DN<6>
  \dqs6_b_t||tdqs6_b_t\  = M_D_CPU1_SB_DQS_DP<6>
  VSS114  = GND
  DQ14_B  = M_D_CPU1_SB_DQ<14>
  VSS115  = GND
  DQ15_B  = M_D_CPU1_SB_DQ<15>
  VSS116  = GND
  DQ18_B  = M_D_CPU1_SB_DQ<18>
  VSS117  = GND
  DQ19_B  = M_D_CPU1_SB_DQ<19>
  VSS118  = GND
  \dqs7_b_c||tdqs7_b_c\  = M_D_CPU1_SB_DQS_DN<7>
  \dqs7_b_t||tdqs7_b_t\  = M_D_CPU1_SB_DQS_DP<7>
  VSS119  = GND
  DQ22_B  = M_D_CPU1_SB_DQ<22>
  VSS120  = GND
  DQ23_B  = M_D_CPU1_SB_DQ<23>
  VSS121  = GND
  DQ26_B  = M_D_CPU1_SB_DQ<26>
  VSS122  = GND
  DQ27_B  = M_D_CPU1_SB_DQ<27>
  VSS123  = GND
  \dqs8_b_c||tdqs8_b_c\  = M_D_CPU1_SB_DQS_DN<8>
  \dqs8_b_t||tdqs8_b_t\  = M_D_CPU1_SB_DQS_DP<8>
  VSS124  = GND
  DQ30_B  = M_D_CPU1_SB_DQ<30>
  VSS125  = GND
  DQ31_B  = M_D_CPU1_SB_DQ<31>
  VSS126  = GND
  G1  = GND
  G2  = GND
  G3  = GND

(kicad_pcb
	(version 20260206)
	(generator "pcbnew")
	(generator_version "10.0")
	(general
		(thickness 1.6)
		(legacy_teardrops no)
	)
	(paper "A4")
	(title_block
		(title "04192023_DAF0TMB3IC0_F0TG_MB_C_brd_V02_OCP.brd")
		(comment 1 "Grand Teton / footprint 3579 of 8354 (J30), pads 139-184 of 291")
	)
	(layers
		(0 "F.Cu" signal "TOP")
		(4 "In1.Cu" signal "GND")
		(6 "In2.Cu" signal "IN1")
		(8 "In3.Cu" signal "GND1")
		(10 "In4.Cu" signal "IN2")
		(12 "In5.Cu" signal "GND2")
		(14 "In6.Cu" signal "IN3")
		(16 "In7.Cu" signal "GND3")
		(18 "In8.Cu" signal "VCC")
		(20 "In9.Cu" signal "VCC1")
		(22 "In10.Cu" signal "GND4")
		(24 "In11.Cu" signal "IN4")
		(26 "In12.Cu" signal "GND5")
		(28 "In13.Cu" signal "IN5")
		(30 "In14.Cu" signal "GND6")
		(32 "In15.Cu" signal "IN6")
		(34 "In16.Cu" signal "GND7")
		(2 "B.Cu" signal "BOTTOM")
		(9 "F.Adhes" user "F.Adhesive")
		(11 "B.Adhes" user "B.Adhesive")
		(13 "F.Paste" user "Package Geometry/Pastemask Top")
		(15 "B.Paste" user "Package Geometry/Pastemask Bottom")
		(5 "F.SilkS" user "Ref Des/Silkscreen Top")
		(7 "B.SilkS" user "Ref Des/Silkscreen Bottom")
		(1 "F.Mask" user "Board Geometry/Soldermask Top")
		(3 "B.Mask" user "Board Geometry/Soldermask Bottom")
		(17 "Dwgs.User" user "User.Drawings")
		(19 "Cmts.User" user "User.Comments")
		(21 "Eco1.User" user "User.Eco1")
		(23 "Eco2.User" user "User.Eco2")
		(25 "Edge.Cuts" user "Board Geometry/Outline")
		(27 "Margin" user)
		(31 "F.CrtYd" user "Package Geometry/Place Bound Top")
		(29 "B.CrtYd" user "Package Geometry/Place Bound Bottom")
		(35 "F.Fab" user "Ref Des/Assembly Top")
		(33 "B.Fab" user "Ref Des/Assembly Bottom")
	)
	(footprint ""
		(layer "F.Cu")
		(at 34.74593 -255.560322 180)
		(property "Reference" "J30"
			(at 3.12293 -81.850992 0)
			(unlocked yes)
			(layer "F.SilkS")
			(effects
				(font
					(size 0.7874 0.5842)
					(thickness 0.1524)
				)
			)
		)
		(property "Value" ""
			(at 0 0 180)
			(layer "F.Fab")
			(effects
				(font
					(size 1.27 1.27)
				)
			)
		)
		(duplicate_pad_numbers_are_jumpers no)
		(pad "139" smd rect
			(at -2.050034 59.075066 90)
			(size 0.519938 1.4986)
			(layers "F.Cu" "F.Mask" "F.Paste")
			(net "GND")
		)
		(pad "140" smd rect
			(at -2.050034 59.92495 90)
			(size 0.519938 1.4986)
			(layers "F.Cu" "F.Mask" "F.Paste")
			(net "M_D_CPU1_SB_DQ<28>")
		)
		(pad "141" smd rect
			(at -2.050034 60.775088 90)
			(size 0.519938 1.4986)
			(layers "F.Cu" "F.Mask" "F.Paste")
			(net "GND")
		)
		(pad "142" smd rect
			(at -2.050034 61.624972 90)
			(size 0.519938 1.4986)
			(layers "F.Cu" "F.Mask" "F.Paste")
			(net "M_D_CPU1_SB_DQ<29>")
		)
		(pad "143" smd rect
			(at -2.050034 62.47511 90)
			(size 0.519938 1.4986)
			(layers "F.Cu" "F.Mask" "F.Paste")
			(net "GND")
		)
		(pad "144" smd rect
			(at -2.050034 63.324994 90)
			(size 0.519938 1.4986)
			(layers "F.Cu" "F.Mask" "F.Paste")
			(net "Net_2299")
		)
		(pad "145" smd rect
			(at 2.050034 -63.324994 90)
			(size 0.519938 1.4986)
			(layers "F.Cu" "F.Mask" "F.Paste")
			(net "P12V_MEM_CPU1")
		)
		(pad "146" smd rect
			(at 2.050034 -62.47511 90)
			(size 0.519938 1.4986)
			(layers "F.Cu" "F.Mask" "F.Paste")
			(net "P12V_MEM_CPU1")
		)
		(pad "147" smd rect
			(at 2.050034 -61.624972 90)
			(size 0.519938 1.4986)
			(layers "F.Cu" "F.Mask" "F.Paste")
			(net "PWRGD_CHD_CPU1_DIMM")
		)
		(pad "148" smd rect
			(at 2.050034 -60.775088 90)
			(size 0.519938 1.4986)
			(layers "F.Cu" "F.Mask" "F.Paste")
			(net "PD_CHD_CPU1_DIMM_SAA")
		)
		(pad "149" smd rect
			(at 2.050034 -59.92495 90)
			(size 0.519938 1.4986)
			(layers "F.Cu" "F.Mask" "F.Paste")
			(net "Net_2300")
		)
		(pad "150" smd rect
			(at 2.050034 -59.075066 90)
			(size 0.519938 1.4986)
			(layers "F.Cu" "F.Mask" "F.Paste")
			(net "Net_2301")
		)
		(pad "151" smd rect
			(at 2.050034 -58.224928 90)
			(size 0.519938 1.4986)
			(layers "F.Cu" "F.Mask" "F.Paste")
			(net "GND")
		)
		(pad "152" smd rect
			(at 2.050034 -57.375044 90)
			(size 0.519938 1.4986)
			(layers "F.Cu" "F.Mask" "F.Paste")
			(net "M_D_CPU1_SA_DQ<2>")
		)
		(pad "153" smd rect
			(at 2.050034 -56.524906 90)
			(size 0.519938 1.4986)
			(layers "F.Cu" "F.Mask" "F.Paste")
			(net "GND")
		)
		(pad "154" smd rect
			(at 2.050034 -55.675022 90)
			(size 0.519938 1.4986)
			(layers "F.Cu" "F.Mask" "F.Paste")
			(net "M_D_CPU1_SA_DQ<3>")
		)
		(pad "155" smd rect
			(at 2.050034 -54.824884 90)
			(size 0.519938 1.4986)
			(layers "F.Cu" "F.Mask" "F.Paste")
			(net "GND")
		)
		(pad "156" smd rect
			(at 2.050034 -53.975 90)
			(size 0.519938 1.4986)
			(layers "F.Cu" "F.Mask" "F.Paste")
			(net "M_D_CPU1_SA_DQS_DN<5>")
		)
		(pad "157" smd rect
			(at 2.050034 -53.125116 90)
			(size 0.519938 1.4986)
			(layers "F.Cu" "F.Mask" "F.Paste")
			(net "M_D_CPU1_SA_DQS_DP<5>")
		)
		(pad "158" smd rect
			(at 2.050034 -52.274978 90)
			(size 0.519938 1.4986)
			(layers "F.Cu" "F.Mask" "F.Paste")
			(net "GND")
		)
		(pad "159" smd rect
			(at 2.050034 -51.425094 90)
			(size 0.519938 1.4986)
			(layers "F.Cu" "F.Mask" "F.Paste")
			(net "M_D_CPU1_SA_DQ<6>")
		)
		(pad "160" smd rect
			(at 2.050034 -50.574956 90)
			(size 0.519938 1.4986)
			(layers "F.Cu" "F.Mask" "F.Paste")
			(net "GND")
		)
		(pad "161" smd rect
			(at 2.050034 -49.725072 90)
			(size 0.519938 1.4986)
			(layers "F.Cu" "F.Mask" "F.Paste")
			(net "M_D_CPU1_SA_DQ<7>")
		)
		(pad "162" smd rect
			(at 2.050034 -48.874934 90)
			(size 0.519938 1.4986)
			(layers "F.Cu" "F.Mask" "F.Paste")
			(net "GND")
		)
		(pad "163" smd rect
			(at 2.050034 -48.02505 90)
			(size 0.519938 1.4986)
			(layers "F.Cu" "F.Mask" "F.Paste")
			(net "M_D_CPU1_SA_DQ<10>")
		)
		(pad "164" smd rect
			(at 2.050034 -47.174912 90)
			(size 0.519938 1.4986)
			(layers "F.Cu" "F.Mask" "F.Paste")
			(net "GND")
		)
		(pad "165" smd rect
			(at 2.050034 -46.325028 90)
			(size 0.519938 1.4986)
			(layers "F.Cu" "F.Mask" "F.Paste")
			(net "M_D_CPU1_SA_DQ<11>")
		)
		(pad "166" smd rect
			(at 2.050034 -45.47489 90)
			(size 0.519938 1.4986)
			(layers "F.Cu" "F.Mask" "F.Paste")
			(net "GND")
		)
		(pad "167" smd rect
			(at 2.050034 -44.625006 90)
			(size 0.519938 1.4986)
			(layers "F.Cu" "F.Mask" "F.Paste")
			(net "M_D_CPU1_SA_DQS_DN<6>")
		)
		(pad "168" smd rect
			(at 2.050034 -43.775122 90)
			(size 0.519938 1.4986)
			(layers "F.Cu" "F.Mask" "F.Paste")
			(net "M_D_CPU1_SA_DQS_DP<6>")
		)
		(pad "169" smd rect
			(at 2.050034 -42.924984 90)
			(size 0.519938 1.4986)
			(layers "F.Cu" "F.Mask" "F.Paste")
			(net "GND")
		)
		(pad "170" smd rect
			(at 2.050034 -42.0751 90)
			(size 0.519938 1.4986)
			(layers "F.Cu" "F.Mask" "F.Paste")
			(net "M_D_CPU1_SA_DQ<14>")
		)
		(pad "171" smd rect
			(at 2.050034 -41.224962 90)
			(size 0.519938 1.4986)
			(layers "F.Cu" "F.Mask" "F.Paste")
			(net "GND")
		)
		(pad "172" smd rect
			(at 2.050034 -40.375078 90)
			(size 0.519938 1.4986)
			(layers "F.Cu" "F.Mask" "F.Paste")
			(net "M_D_CPU1_SA_DQ<15>")
		)
		(pad "173" smd rect
			(at 2.050034 -39.52494 90)
			(size 0.519938 1.4986)
			(layers "F.Cu" "F.Mask" "F.Paste")
			(net "GND")
		)
		(pad "174" smd rect
			(at 2.050034 -38.675056 90)
			(size 0.519938 1.4986)
			(layers "F.Cu" "F.Mask" "F.Paste")
			(net "M_D_CPU1_SA_DQ<18>")
		)
		(pad "175" smd rect
			(at 2.050034 -37.824918 90)
			(size 0.519938 1.4986)
			(layers "F.Cu" "F.Mask" "F.Paste")
			(net "GND")
		)
		(pad "176" smd rect
			(at 2.050034 -36.975034 90)
			(size 0.519938 1.4986)
			(layers "F.Cu" "F.Mask" "F.Paste")
			(net "M_D_CPU1_SA_DQ<19>")
		)
		(pad "177" smd rect
			(at 2.050034 -36.124896 90)
			(size 0.519938 1.4986)
			(layers "F.Cu" "F.Mask" "F.Paste")
			(net "GND")
		)
		(pad "178" smd rect
			(at 2.050034 -35.275012 90)
			(size 0.519938 1.4986)
			(layers "F.Cu" "F.Mask" "F.Paste")
			(net "M_D_CPU1_SA_DQS_DN<7>")
		)
		(pad "179" smd rect
			(at 2.050034 -34.425128 90)
			(size 0.519938 1.4986)
			(layers "F.Cu" "F.Mask" "F.Paste")
			(net "M_D_CPU1_SA_DQS_DP<7>")
		)
		(pad "180" smd rect
			(at 2.050034 -33.57499 90)
			(size 0.519938 1.4986)
			(layers "F.Cu" "F.Mask" "F.Paste")
			(net "GND")
		)
		(pad "181" smd rect
			(at 2.050034 -32.725106 90)
			(size 0.519938 1.4986)
			(layers "F.Cu" "F.Mask" "F.Paste")
			(net "M_D_CPU1_SA_DQ<22>")
		)
		(pad "182" smd rect
			(at 2.050034 -31.874968 90)
			(size 0.519938 1.4986)
			(layers "F.Cu" "F.Mask" "F.Paste")
			(net "GND")
		)
		(pad "183" smd rect
			(at 2.050034 -31.025084 90)
			(size 0.519938 1.4986)
			(layers "F.Cu" "F.Mask" "F.Paste")
			(net "M_D_CPU1_SA_DQ<23>")
		)
		(pad "184" smd rect
			(at 2.050034 -30.174946 90)
			(size 0.519938 1.4986)
			(layers "F.Cu" "F.Mask" "F.Paste")
			(net "GND")
		)
	)
)
